(kicad_pcb
	(version 20260206)
	(generator "pcbnew")
	(generator_version "10.0")
	(general
		(thickness 1.21888)
		(legacy_teardrops no)
	)
	(paper "A4")
	(title_block
		(title "timecard-v8 — TimeCard-DC-V8_EXP.PcbDoc")
		(comment 1 "Time Appliance Project (Time Card) / footprints 178-186 of 288")
	)
	(layers
		(0 "F.Cu" signal "TOP")
		(4 "In1.Cu" signal "SGND")
		(6 "In2.Cu" signal "IN1")
		(8 "In3.Cu" signal "IN2")
		(10 "In4.Cu" signal "SGND1")
		(2 "B.Cu" signal "BOTTOM")
		(9 "F.Adhes" user "F.Adhesive")
		(11 "B.Adhes" user "B.Adhesive")
		(13 "F.Paste" user "Top Paste")
		(15 "B.Paste" user "Bottom Paste")
		(5 "F.SilkS" user "Top Overlay")
		(7 "B.SilkS" user "Bottom Overlay")
		(1 "F.Mask" user "Top Solder")
		(3 "B.Mask" user "Bottom Solder")
		(17 "Dwgs.User" user "User.Drawings")
		(19 "Cmts.User" user "User.Comments")
		(21 "Eco1.User" user "User.Eco1")
		(23 "Eco2.User" user "User.Eco2")
		(25 "Edge.Cuts" user)
		(27 "Margin" user)
		(31 "F.CrtYd" user "Top Courtyard")
		(29 "B.CrtYd" user "Bottom Courtyard")
		(35 "F.Fab" user "Top Component Center")
		(33 "B.Fab" user "Bottom Component Center")
	)
	(footprint "Vault:FP-BLM18-0_15-t0_8-IPC_A"
		(layer "F.Cu")
		(at 233.9261 81.5162 -90)
		(property "Reference" "FB1"
			(at 2.128605 -1.673069 270)
			(unlocked yes)
			(layer "F.SilkS")
			(effects
				(font
					(size 0.762 0.762)
					(thickness 0.2286)
				)
			)
		)
		(property "Value" "600ohm_1.3A_0603"
			(at 10.14352 2.744961 270)
			(unlocked yes)
			(layer "F.SilkS")
			(hide yes)
			(effects
				(font
					(size 0.762 0.762)
					(thickness 0.2286)
				)
			)
		)
		(sheetname "USBUart_DipSelects")
		(sheetfile "USBUart_DipSelects.kicad_sch")
		(duplicate_pad_numbers_are_jumpers no)
		(fp_line
			(start 1.42911 0.92911)
			(end -1.42911 0.92911)
			(stroke
				(width 0.2)
				(type solid)
			)
			(layer "F.SilkS")
		)
		(fp_line
			(start 1.42911 -0.92911)
			(end -1.42911 -0.92911)
			(stroke
				(width 0.2)
				(type solid)
			)
			(layer "F.SilkS")
		)
		(fp_line
			(start -1.92911 1.02911)
			(end -1.92911 -1.02911)
			(stroke
				(width 0.2)
				(type solid)
			)
			(layer "F.CrtYd")
		)
		(fp_line
			(start 1.92911 1.02911)
			(end -1.92911 1.02911)
			(stroke
				(width 0.2)
				(type solid)
			)
			(layer "F.CrtYd")
		)
		(fp_line
			(start 1.92911 1.02911)
			(end 1.92911 -1.02911)
			(stroke
				(width 0.2)
				(type solid)
			)
			(layer "F.CrtYd")
		)
		(fp_line
			(start 1.92911 -1.02911)
			(end -1.92911 -1.02911)
			(stroke
				(width 0.2)
				(type solid)
			)
			(layer "F.CrtYd")
		)
		(fp_line
			(start -1.92911 1.02911)
			(end -1.92911 -1.02911)
			(stroke
				(width 0.2)
				(type solid)
			)
			(layer "F.Fab")
		)
		(fp_line
			(start 1.92911 1.02911)
			(end -1.92911 1.02911)
			(stroke
				(width 0.2)
				(type solid)
			)
			(layer "F.Fab")
		)
		(fp_line
			(start 1.92911 1.02911)
			(end 1.92911 -1.02911)
			(stroke
				(width 0.2)
				(type solid)
			)
			(layer "F.Fab")
		)
		(fp_line
			(start 0 0.5)
			(end 0 -0.5)
			(stroke
				(width 0.1)
				(type solid)
			)
			(layer "F.Fab")
		)
		(fp_line
			(start 0.5 0)
			(end -0.5 0)
			(stroke
				(width 0.1)
				(type solid)
			)
			(layer "F.Fab")
		)
		(fp_line
			(start 1.92911 -1.02911)
			(end -1.92911 -1.02911)
			(stroke
				(width 0.2)
				(type solid)
			)
			(layer "F.Fab")
		)
		(fp_text user "${REFERENCE}"
			(at -0.00001 0.10711 270)
			(unlocked yes)
			(layer "F.Fab")
			(effects
				(font
					(face "Arial")
					(size 0.63 0.63)
					(thickness 0.1)
				)
				(justify left bottom)
			)
		)
		(pad "1" smd rect
			(at -0.77608 0 270)
			(size 1.30606 1.05822)
			(layers "F.Cu" "F.Mask" "F.Paste")
			(net "USB_VBUS")
			(solder_mask_margin 0)
			(solder_paste_margin 0)
		)
		(pad "2" smd rect
			(at 0.77608 0 270)
			(size 1.30606 1.05822)
			(layers "F.Cu" "F.Mask" "F.Paste")
			(net "FTDI_VBUS")
			(solder_mask_margin 0)
			(solder_paste_margin 0)
		)
	)
	(footprint "Vault:RESC1005X40X25LL05T10"
		(layer "F.Cu")
		(at 122.8261 84.4162 90)
		(property "Reference" "R104"
			(at -2.0714 -0.073079 90)
			(unlocked yes)
			(layer "F.SilkS")
			(effects
				(font
					(size 0.762 0.762)
					(thickness 0.2286)
				)
			)
		)
		(property "Value" "DNI_49.9_1%_0402"
			(at -2.579871 11.74372 0)
			(unlocked yes)
			(layer "F.SilkS")
			(hide yes)
			(effects
				(font
					(size 0.762 0.762)
					(thickness 0.2286)
				)
			)
		)
		(sheetname "USBUart_DipSelects")
		(sheetfile "USBUart_DipSelects.kicad_sch")
		(duplicate_pad_numbers_are_jumpers no)
		(pad "1" smd rect
			(at -0.375 0 180)
			(size 0.45 0.5)
			(layers "F.Cu" "F.Mask" "F.Paste")
			(net "FPGA_MAC_PPS_OUT-")
		)
		(pad "2" smd rect
			(at 0.375 0 180)
			(size 0.45 0.5)
			(layers "F.Cu" "F.Mask" "F.Paste")
			(net "MAC_PPS_OUT")
		)
	)
	(footprint "Vault:RESC1608X55X30NL15T15"
		(layer "F.Cu")
		(at 84.3761 125.8662 -90)
		(property "Reference" "R16"
			(at 2.7714 -0.026931 90)
			(unlocked yes)
			(layer "F.SilkS")
			(effects
				(font
					(size 0.762 0.762)
					(thickness 0.2286)
				)
			)
		)
		(property "Value" "4.7K"
			(at 0.558471 -4.82535 0)
			(unlocked yes)
			(layer "F.SilkS")
			(hide yes)
			(effects
				(font
					(size 0.762 0.762)
					(thickness 0.2286)
				)
			)
		)
		(sheetname "USER_IO")
		(sheetfile "USER_IO.kicad_sch")
		(duplicate_pad_numbers_are_jumpers no)
		(pad "1" smd rect
			(at -0.75 0)
			(size 0.95 0.95)
			(layers "F.Cu" "F.Mask" "F.Paste")
			(net "ANT3_IO_OUT")
		)
		(pad "2" smd rect
			(at 0.75 0)
			(size 0.95 0.95)
			(layers "F.Cu" "F.Mask" "F.Paste")
			(net "+3.3V")
		)
	)
	(footprint "Vault:RESC1005X40X25LL05T10"
		(layer "F.Cu")
		(at 128.6261 81.7162 180)
		(property "Reference" "R106"
			(at -0.8286 1.173069 0)
			(unlocked yes)
			(layer "F.SilkS")
			(effects
				(font
					(size 0.762 0.762)
					(thickness 0.2286)
				)
			)
		)
		(property "Value" "DNI_49.9_1%_0402"
			(at -2.579871 11.74372 90)
			(unlocked yes)
			(layer "F.SilkS")
			(hide yes)
			(effects
				(font
					(size 0.762 0.762)
					(thickness 0.2286)
				)
			)
		)
		(sheetname "USBUart_DipSelects")
		(sheetfile "USBUart_DipSelects.kicad_sch")
		(duplicate_pad_numbers_are_jumpers no)
		(pad "1" smd rect
			(at -0.375 0 270)
			(size 0.45 0.5)
			(layers "F.Cu" "F.Mask" "F.Paste")
			(net "FPGA_MAC_PPS_IN0-")
		)
		(pad "2" smd rect
			(at 0.375 0 270)
			(size 0.45 0.5)
			(layers "F.Cu" "F.Mask" "F.Paste")
			(net "MAC_PPS_IN")
		)
	)
	(footprint "Vault:TECO-1909763-1_V"
		(layer "F.Cu")
		(at 74.3761 121.8662 -90)
		(property "Reference" "J3"
			(at -2.973069 1.271395 0)
			(unlocked yes)
			(layer "F.SilkS")
			(effects
				(font
					(size 0.762 0.762)
					(thickness 0.2286)
				)
			)
		)
		(property "Value" "1909763-1"
			(at 4.582685 3.722871 270)
			(unlocked yes)
			(layer "F.SilkS")
			(hide yes)
			(effects
				(font
					(size 0.762 0.762)
					(thickness 0.2286)
				)
			)
		)
		(sheetname "USER_IO")
		(sheetfile "USER_IO.kicad_sch")
		(duplicate_pad_numbers_are_jumpers no)
		(fp_line
			(start 0.55 -1.3)
			(end -0.55 -1.3)
			(stroke
				(width 0.2)
				(type solid)
			)
			(layer "F.SilkS")
		)
		(fp_circle
			(center -1.778 1.65)
			(end -1.903 1.65)
			(stroke
				(width 0.25)
				(type solid)
			)
			(fill no)
			(layer "F.SilkS")
		)
		(pad "1" smd rect
			(at -1.475 0 270)
			(size 1.05 2.2)
			(layers "F.Cu" "F.Mask" "F.Paste")
			(net "GND")
		)
		(pad "2" smd rect
			(at 0 1.525 270)
			(size 1 1.05)
			(layers "F.Cu" "F.Mask" "F.Paste")
			(net "NetAN3_1")
		)
		(pad "3" smd rect
			(at 1.475 0 270)
			(size 1.05 2.2)
			(layers "F.Cu" "F.Mask" "F.Paste")
			(net "GND")
		)
	)
	(footprint "Vault:FP-T495D107K016ATE125-MFG"
		(layer "F.Cu")
		(at 226.5261 119.7162)
		(property "Reference" "C79"
			(at 2.9286 -2.973069 0)
			(unlocked yes)
			(layer "F.SilkS")
			(effects
				(font
					(size 0.762 0.762)
					(thickness 0.2286)
				)
			)
		)
		(property "Value" "100uF_16V_2917"
			(at -5.818351 8.010455 270)
			(unlocked yes)
			(layer "F.SilkS")
			(hide yes)
			(effects
				(font
					(size 0.762 0.762)
					(thickness 0.2286)
				)
			)
		)
		(sheetname "POWER")
		(sheetfile "POWER.kicad_sch")
		(duplicate_pad_numbers_are_jumpers no)
		(fp_line
			(start -3.8 -2.3)
			(end 3.8 -2.3)
			(stroke
				(width 0.2)
				(type solid)
			)
			(layer "F.SilkS")
		)
		(fp_line
			(start -3.8 -1.54)
			(end -3.8 -2.3)
			(stroke
				(width 0.2)
				(type solid)
			)
			(layer "F.SilkS")
		)
		(fp_line
			(start -3.8 2.3)
			(end -3.8 1.54)
			(stroke
				(width 0.2)
				(type solid)
			)
			(layer "F.SilkS")
		)
		(fp_line
			(start -3.8 2.3)
			(end 3.8 2.3)
			(stroke
				(width 0.2)
				(type solid)
			)
			(layer "F.SilkS")
		)
		(fp_line
			(start 3.8 -1.54)
			(end 3.8 -2.3)
			(stroke
				(width 0.2)
				(type solid)
			)
			(layer "F.SilkS")
		)
		(fp_line
			(start 3.8 2.3)
			(end 3.8 1.54)
			(stroke
				(width 0.2)
				(type solid)
			)
			(layer "F.SilkS")
		)
		(fp_line
			(start 4.4 0)
			(end 5 0)
			(stroke
				(width 0.2)
				(type solid)
			)
			(layer "F.SilkS")
		)
		(fp_line
			(start 4.7 0.3)
			(end 4.7 -0.3)
			(stroke
				(width 0.2)
				(type solid)
			)
			(layer "F.SilkS")
		)
		(fp_line
			(start -4.105 -2.4)
			(end 4.105 -2.4)
			(stroke
				(width 0.2)
				(type solid)
			)
			(layer "F.CrtYd")
		)
		(fp_line
			(start -4.105 2.4)
			(end -4.105 -2.4)
			(stroke
				(width 0.2)
				(type solid)
			)
			(layer "F.CrtYd")
		)
		(fp_line
			(start -4.105 2.4)
			(end 4.105 2.4)
			(stroke
				(width 0.2)
				(type solid)
			)
			(layer "F.CrtYd")
		)
		(fp_line
			(start 4.105 2.4)
			(end 4.105 -2.4)
			(stroke
				(width 0.2)
				(type solid)
			)
			(layer "F.CrtYd")
		)
		(fp_line
			(start -4.105 -2.4)
			(end 4.105 -2.4)
			(stroke
				(width 0.2)
				(type solid)
			)
			(layer "F.Fab")
		)
		(fp_line
			(start -4.105 2.4)
			(end -4.105 -2.4)
			(stroke
				(width 0.2)
				(type solid)
			)
			(layer "F.Fab")
		)
		(fp_line
			(start -4.105 2.4)
			(end 4.105 2.4)
			(stroke
				(width 0.2)
				(type solid)
			)
			(layer "F.Fab")
		)
		(fp_line
			(start -0.5 0)
			(end 0.5 0)
			(stroke
				(width 0.1)
				(type solid)
			)
			(layer "F.Fab")
		)
		(fp_line
			(start 0 0.5)
			(end 0 -0.5)
			(stroke
				(width 0.1)
				(type solid)
			)
			(layer "F.Fab")
		)
		(fp_line
			(start 4.105 2.4)
			(end 4.105 -2.4)
			(stroke
				(width 0.2)
				(type solid)
			)
			(layer "F.Fab")
		)
		(fp_text user "${REFERENCE}"
			(at 0 0.28425 360)
			(unlocked yes)
			(layer "F.Fab")
			(effects
				(font
					(face "Arial")
					(size 0.63 0.63)
					(thickness 0.1)
				)
				(justify left bottom)
			)
		)
		(pad "1" smd rect
			(at -3.01 0)
			(size 1.99 2.33)
			(layers "F.Cu" "F.Mask" "F.Paste")
			(net "GND")
			(solder_mask_margin 0)
			(solder_paste_margin 0)
		)
		(pad "2" smd rect
			(at 3.01 0)
			(size 1.99 2.33)
			(layers "F.Cu" "F.Mask" "F.Paste")
			(net "+3.3V")
			(solder_mask_margin 0)
			(solder_paste_margin 0)
		)
	)
	(footprint "GNSS:GNSS Header 16-pin"
		(layer "F.Cu")
		(at 80.1536 74.3286)
		(property "Reference" "J6"
			(at 5.285479 3.491555 270)
			(unlocked yes)
			(layer "F.SilkS")
			(effects
				(font
					(size 0.762 0.762)
					(thickness 0.2286)
				)
			)
		)
		(property "Value" "GNSS Header 16-pin"
			(at 6.740165 4.840511 0)
			(unlocked yes)
			(layer "F.SilkS")
			(hide yes)
			(effects
				(font
					(size 0.762 0.762)
					(thickness 0.2286)
				)
			)
		)
		(sheetname "GPS_IMU_SENSORS")
		(sheetfile "GPS_IMU_SENSORS.kicad_sch")
		(duplicate_pad_numbers_are_jumpers no)
		(fp_line
			(start -0.5 -7.5)
			(end 8.5 -7.5)
			(stroke
				(width 0.0254)
				(type solid)
			)
			(layer "F.SilkS")
		)
		(fp_line
			(start -0.5 0.5)
			(end -0.5 -7.5)
			(stroke
				(width 0.0254)
				(type solid)
			)
			(layer "F.SilkS")
		)
		(fp_line
			(start -0.5 0.5)
			(end 8.5 0.5)
			(stroke
				(width 0.0254)
				(type solid)
			)
			(layer "F.SilkS")
		)
		(fp_line
			(start 8.5 0.5)
			(end 8.5 -7.5)
			(stroke
				(width 0.0254)
				(type solid)
			)
			(layer "F.SilkS")
		)
		(fp_circle
			(center 0 -0.5)
			(end 0 -0.5254)
			(stroke
				(width 0.508)
				(type solid)
			)
			(fill no)
			(layer "F.SilkS")
		)
		(fp_text user "Orig 2x4"
			(at 9.610805 -0.2286 90)
			(unlocked yes)
			(layer "F.SilkS")
			(effects
				(font
					(size 0.762 0.762)
					(thickness 0.2286)
				)
				(justify left bottom)
			)
		)
		(pad "0" thru_hole circle
			(at 4 -13.49998 270)
			(size 0 0)
			(drill 0.76)
			(layers "*.Cu" "*.Mask")
			(remove_unused_layers no)
			(thermal_bridge_angle 90)
		)
		(pad "0" thru_hole circle
			(at 4 -1.5 270)
			(size 0 0)
			(drill 0.76)
			(layers "*.Cu" "*.Mask")
			(remove_unused_layers no)
			(thermal_bridge_angle 90)
		)
		(pad "1" smd rect
			(at 1.7775 -0.5 270)
			(size 1.12 2.105)
			(layers "F.Cu" "F.Mask" "F.Paste")
			(net "+5.0V")
		)
		(pad "2" smd rect
			(at 6.2225 -0.5 270)
			(size 1.12 2.105)
			(layers "F.Cu" "F.Mask" "F.Paste")
			(net "+3.3V")
		)
		(pad "3" smd rect
			(at 1.7775 -2.5 270)
			(size 1.12 2.105)
			(layers "F.Cu" "F.Mask" "F.Paste")
			(net "GPS1_TX")
		)
		(pad "4" smd rect
			(at 6.2225 -2.5 270)
			(size 1.12 2.105)
			(layers "F.Cu" "F.Mask" "F.Paste")
			(net "GPS1_RST")
		)
		(pad "5" smd rect
			(at 1.7775 -4.5 270)
			(size 1.12 2.105)
			(layers "F.Cu" "F.Mask" "F.Paste")
			(net "GPS1_RX")
		)
		(pad "6" smd rect
			(at 6.2225 -4.5 270)
			(size 1.12 2.105)
			(layers "F.Cu" "F.Mask" "F.Paste")
			(net "GPS1_TP1")
		)
		(pad "7" smd rect
			(at 1.7775 -6.5 270)
			(size 1.12 2.105)
			(layers "F.Cu" "F.Mask" "F.Paste")
			(net "GPS1_TP2")
		)
		(pad "8" smd rect
			(at 6.2225 -6.5 270)
			(size 1.12 2.105)
			(layers "F.Cu" "F.Mask" "F.Paste")
			(net "GND")
		)
		(pad "9" smd rect
			(at 1.7775 -8.50001 270)
			(size 1.12 2.105)
			(layers "F.Cu" "F.Mask" "F.Paste")
			(net "+5.0V")
		)
		(pad "10" smd rect
			(at 6.2225 -8.50001 270)
			(size 1.12 2.105)
			(layers "F.Cu" "F.Mask" "F.Paste")
			(net "+3.3V")
		)
		(pad "11" smd rect
			(at 1.7775 -10.50001 270)
			(size 1.12 2.105)
			(layers "F.Cu" "F.Mask" "F.Paste")
			(net "GPS1_PIN11")
		)
		(pad "12" smd rect
			(at 6.2225 -10.50001 270)
			(size 1.12 2.105)
			(layers "F.Cu" "F.Mask" "F.Paste")
			(net "GPS1_PIN12")
		)
		(pad "13" smd rect
			(at 1.7775 -12.5 270)
			(size 1.12 2.105)
			(layers "F.Cu" "F.Mask" "F.Paste")
			(net "GPS1_PIN13")
		)
		(pad "14" smd rect
			(at 6.2225 -12.5 270)
			(size 1.12 2.105)
			(layers "F.Cu" "F.Mask" "F.Paste")
			(net "GPS1_PIN14")
		)
		(pad "15" smd rect
			(at 1.7775 -14.5 270)
			(size 1.12 2.105)
			(layers "F.Cu" "F.Mask" "F.Paste")
			(net "GPS1_PIN15")
		)
		(pad "16" smd rect
			(at 6.2225 -14.5 270)
			(size 1.12 2.105)
			(layers "F.Cu" "F.Mask" "F.Paste")
			(net "GND")
		)
	)
	(footprint "Vault:CAPC1608X87X45ML20T05"
		(layer "F.Cu")
		(at 176.8761 87.0786 -90)
		(property "Reference" "C25"
			(at -2.4338 -0.023069 270)
			(unlocked yes)
			(layer "F.SilkS")
			(effects
				(font
					(size 0.762 0.762)
					(thickness 0.2286)
				)
			)
		)
		(property "Value" "0.1uF"
			(at 2.069035 2.630671 270)
			(unlocked yes)
			(layer "F.SilkS")
			(hide yes)
			(effects
				(font
					(size 0.762 0.762)
					(thickness 0.2286)
				)
			)
		)
		(sheetname "GPS_IMU_SENSORS")
		(sheetfile "GPS_IMU_SENSORS.kicad_sch")
		(duplicate_pad_numbers_are_jumpers no)
		(pad "1" smd rect
			(at -0.7 0)
			(size 1.1 1.05)
			(layers "F.Cu" "F.Mask" "F.Paste")
			(net "GND")
		)
		(pad "2" smd rect
			(at 0.7 0)
			(size 1.1 1.05)
			(layers "F.Cu" "F.Mask" "F.Paste")
			(net "+3.3V")
		)
	)
	(footprint "Vault:RESC1005X40X25ML05T10"
		(layer "F.Cu")
		(at 202.8511 127.5162)
		(property "Reference" "R74"
			(at -3.1964 4.226921 0)
			(unlocked yes)
			(layer "F.SilkS")
			(effects
				(font
					(size 0.762 0.762)
					(thickness 0.2286)
				)
			)
		)
		(property "Value" "2.21_1%_0402"
			(at -2.884681 8.544315 270)
			(unlocked yes)
			(layer "F.SilkS")
			(hide yes)
			(effects
				(font
					(size 0.762 0.762)
					(thickness 0.2286)
				)
			)
		)
		(sheetname "POWER")
		(sheetfile "POWER.kicad_sch")
		(duplicate_pad_numbers_are_jumpers no)
		(pad "1" smd rect
			(at -0.475 0 90)
			(size 0.65 0.7)
			(layers "F.Cu" "F.Mask" "F.Paste")
			(net "+12V")
		)
		(pad "2" smd rect
			(at 0.475 0 90)
			(size 0.65 0.7)
			(layers "F.Cu" "F.Mask" "F.Paste")
			(net "NetC71_1")
		)
	)
)
